# T6G (Grand Teton) — schematic netlist excerpt (pin names and nets, part order shuffled) for the footprints in the layout excerpt that follows; sources: Cadence DE-HDL packaged netlist, KiCad conversion of 04192023_DAF0TMB3IC0_F0TG_MB_C_brd_V02_OCP.brd

X8010  TP_TDR_4P_FTS  TP_TDR_4P_DIP EMPTY  pkg TH  page 260
  S1  = TDR_DIFF_85_IN3_DN
  P1  = T1_GND
  P2  = T1_GND
  S2  = TDR_DIFF_85_IN3_DP

Q133  MOSFET_NCH_DUAL  PJT138K IC  pkg SOT363XD  page 125
  S1  = GND
  G1  = PRSNT_CABLE_GPU_A2_N
  D2  = PRSNT_CABLE_GPU_A2_ISO_N
  S2  = GND
  G2  = PRSNT_CABLE_GPU_A2
  D1  = PRSNT_CABLE_GPU_A2

(kicad_pcb
	(version 20260206)
	(generator "pcbnew")
	(generator_version "10.0")
	(general
		(thickness 1.6)
		(legacy_teardrops no)
	)
	(paper "A4")
	(title_block
		(title "04192023_DAF0TMB3IC0_F0TG_MB_C_brd_V02_OCP.brd")
		(comment 1 "Grand Teton / footprints 3192-3193 of 8354")
	)
	(layers
		(0 "F.Cu" signal "TOP")
		(4 "In1.Cu" signal "GND")
		(6 "In2.Cu" signal "IN1")
		(8 "In3.Cu" signal "GND1")
		(10 "In4.Cu" signal "IN2")
		(12 "In5.Cu" signal "GND2")
		(14 "In6.Cu" signal "IN3")
		(16 "In7.Cu" signal "GND3")
		(18 "In8.Cu" signal "VCC")
		(20 "In9.Cu" signal "VCC1")
		(22 "In10.Cu" signal "GND4")
		(24 "In11.Cu" signal "IN4")
		(26 "In12.Cu" signal "GND5")
		(28 "In13.Cu" signal "IN5")
		(30 "In14.Cu" signal "GND6")
		(32 "In15.Cu" signal "IN6")
		(34 "In16.Cu" signal "GND7")
		(2 "B.Cu" signal "BOTTOM")
		(9 "F.Adhes" user "F.Adhesive")
		(11 "B.Adhes" user "B.Adhesive")
		(13 "F.Paste" user "Package Geometry/Pastemask Top")
		(15 "B.Paste" user "Package Geometry/Pastemask Bottom")
		(5 "F.SilkS" user "Ref Des/Silkscreen Top")
		(7 "B.SilkS" user "Ref Des/Silkscreen Bottom")
		(1 "F.Mask" user "Board Geometry/Soldermask Top")
		(3 "B.Mask" user "Board Geometry/Soldermask Bottom")
		(17 "Dwgs.User" user "User.Drawings")
		(19 "Cmts.User" user "User.Comments")
		(21 "Eco1.User" user "User.Eco1")
		(23 "Eco2.User" user "User.Eco2")
		(25 "Edge.Cuts" user "Board Geometry/Outline")
		(27 "Margin" user)
		(31 "F.CrtYd" user "Package Geometry/Place Bound Top")
		(29 "B.CrtYd" user "Package Geometry/Place Bound Bottom")
		(35 "F.Fab" user "Ref Des/Assembly Top")
		(33 "B.Fab" user "Ref Des/Assembly Bottom")
	)
	(footprint ""
		(layer "F.Cu")
		(at 488.03433 -142.808198 90)
		(property "Reference" "X8010"
			(at -1.947672 1.593342 0)
			(unlocked yes)
			(layer "F.SilkS")
			(effects
				(font
					(size 0.7874 0.5842)
					(thickness 0.1524)
				)
				(justify left)
			)
		)
		(property "Value" ""
			(at 0 0 90)
			(layer "F.Fab")
			(effects
				(font
					(size 1.27 1.27)
				)
			)
		)
		(property "Device Type" "TP_TDR_4P_FTS_TH-TP_TDR_4P_DIP,EMPTY,TP15"
			(at 1.30175 1.27 180)
			(unlocked yes)
			(layer "F.Fab")
			(hide yes)
			(effects
				(font
					(size 0.635 0.4064)
					(thickness 0.1524)
				)
			)
		)
		(property "User Part Number" "N_A"
			(at 1.30175 1.27 180)
			(unlocked yes)
			(layer "Cmts.User")
			(hide yes)
			(effects
				(font
					(size 0.635 0.4064)
					(thickness 0.1524)
				)
			)
		)
		(duplicate_pad_numbers_are_jumpers no)
		(fp_line
			(start 2.54 -1.27)
			(end 0 -1.27)
			(stroke
				(width 0.1524)
				(type default)
			)
			(layer "F.SilkS")
		)
		(fp_line
			(start 0 -1.27)
			(end 0 -0.635)
			(stroke
				(width 0.1524)
				(type default)
			)
			(layer "F.SilkS")
		)
		(fp_line
			(start 2.54 -1.1303)
			(end 2.54 -1.27)
			(stroke
				(width 0.1524)
				(type default)
			)
			(layer "F.SilkS")
		)
		(fp_line
			(start 0 0.635)
			(end 0 1.905)
			(stroke
				(width 0.1524)
				(type default)
			)
			(layer "F.SilkS")
		)
		(fp_line
			(start 2.54 1.4097)
			(end 2.54 1.1303)
			(stroke
				(width 0.1524)
				(type default)
			)
			(layer "F.SilkS")
		)
		(fp_line
			(start 0 3.175)
			(end 0 3.81)
			(stroke
				(width 0.1524)
				(type default)
			)
			(layer "F.SilkS")
		)
		(fp_line
			(start 2.54 3.81)
			(end 2.54 3.6703)
			(stroke
				(width 0.1524)
				(type default)
			)
			(layer "F.SilkS")
		)
		(fp_line
			(start 0 3.81)
			(end 2.54 3.81)
			(stroke
				(width 0.1524)
				(type default)
			)
			(layer "F.SilkS")
		)
		(fp_poly
			(pts
				(xy -2.285746 -0.762) (xy -0.761746 0) (xy -2.285746 0.762)
			)
			(stroke
				(width 0)
				(type default)
			)
			(fill yes)
			(layer "F.SilkS")
		)
		(fp_line
			(start 2.54 -1.27)
			(end 0 -1.27)
			(stroke
				(width 0.1)
				(type default)
			)
			(layer "F.Fab")
		)
		(fp_line
			(start 0 -1.27)
			(end 0 3.81)
			(stroke
				(width 0.1)
				(type default)
			)
			(layer "F.Fab")
		)
		(fp_line
			(start 2.54 3.81)
			(end 2.54 -1.27)
			(stroke
				(width 0.1)
				(type default)
			)
			(layer "F.Fab")
		)
		(fp_line
			(start 0 3.81)
			(end 2.54 3.81)
			(stroke
				(width 0.1)
				(type default)
			)
			(layer "F.Fab")
		)
		(fp_poly
			(pts
				(xy -0.761746 0) (xy -2.285746 -0.762) (xy -2.285746 0.762)
			)
			(stroke
				(width 0)
				(type default)
			)
			(fill yes)
			(layer "F.Fab")
		)
		(pad "1" thru_hole circle
			(at 0 0 90)
			(size 1.0033 1.0033)
			(drill 0.249936)
			(layers "*.Cu" "*.Mask")
			(remove_unused_layers no)
			(net "TDR_DIFF_85_IN3_DN")
			(clearance 0.10795)
			(thermal_gap 0.10795)
			(padstack
				(mode front_inner_back)
				(layer "Inner"
					(shape circle)
					(size 0.8001 0.8001)
					(clearance 0.1524)
				)
				(layer "B.Cu"
					(shape circle)
					(size 1.0033 1.0033)
					(clearance 0.10795)
				)
			)
		)
		(pad "2" thru_hole circle
			(at 2.54 0 90)
			(size 1.9939 1.9939)
			(drill 0.249936)
			(layers "*.Cu" "*.Mask")
			(remove_unused_layers no)
			(net "T1_GND")
			(clearance 0.10795)
			(thermal_gap 0.10795)
			(padstack
				(mode front_inner_back)
				(layer "Inner"
					(shape circle)
					(size 0.8001 0.8001)
					(clearance 0.1524)
				)
				(layer "B.Cu"
					(shape circle)
					(size 1.9939 1.9939)
					(clearance 0.10795)
				)
			)
		)
		(pad "3" thru_hole circle
			(at 2.54 2.54 90)
			(size 1.9939 1.9939)
			(drill 0.249936)
			(layers "*.Cu" "*.Mask")
			(remove_unused_layers no)
			(net "T1_GND")
			(clearance 0.10795)
			(thermal_gap 0.10795)
			(padstack
				(mode front_inner_back)
				(layer "Inner"
					(shape circle)
					(size 0.8001 0.8001)
					(clearance 0.1524)
				)
				(layer "B.Cu"
					(shape circle)
					(size 1.9939 1.9939)
					(clearance 0.10795)
				)
			)
		)
		(pad "4" thru_hole circle
			(at 0 2.54 90)
			(size 1.0033 1.0033)
			(drill 0.249936)
			(layers "*.Cu" "*.Mask")
			(remove_unused_layers no)
			(net "TDR_DIFF_85_IN3_DP")
			(clearance 0.10795)
			(thermal_gap 0.10795)
			(padstack
				(mode front_inner_back)
				(layer "Inner"
					(shape circle)
					(size 0.8001 0.8001)
					(clearance 0.1524)
				)
				(layer "B.Cu"
					(shape circle)
					(size 1.0033 1.0033)
					(clearance 0.10795)
				)
			)
		)
	)
	(footprint ""
		(layer "F.Cu")
		(at 307.470302 -427.141386 -90)
		(property "Reference" "Q133"
			(at 1.452372 -1.958848 90)
			(unlocked yes)
			(layer "F.SilkS")
			(effects
				(font
					(size 0.7874 0.5842)
					(thickness 0.1524)
				)
				(justify left)
			)
		)
		(property "Value" ""
			(at 0 0 270)
			(layer "F.Fab")
			(effects
				(font
					(size 1.27 1.27)
				)
			)
		)
		(duplicate_pad_numbers_are_jumpers no)
		(fp_line
			(start -1.332738 1.100074)
			(end -1.332738 -1.100074)
			(stroke
				(width 0.1524)
				(type default)
			)
			(layer "F.SilkS")
		)
		(fp_line
			(start 1.332738 1.100074)
			(end -1.332738 1.100074)
			(stroke
				(width 0.1524)
				(type default)
			)
			(layer "F.SilkS")
		)
		(fp_line
			(start 0 -0.541274)
			(end 0.4826 -1.100074)
			(stroke
				(width 0.1524)
				(type default)
			)
			(layer "F.SilkS")
		)
		(fp_line
			(start -1.332738 -1.100074)
			(end -0.4826 -1.100074)
			(stroke
				(width 0.1524)
				(type default)
			)
			(layer "F.SilkS")
		)
		(fp_line
			(start -0.4826 -1.100074)
			(end 0 -0.541274)
			(stroke
				(width 0.1524)
				(type default)
			)
			(layer "F.SilkS")
		)
		(fp_line
			(start 0.4826 -1.100074)
			(end 1.332738 -1.100074)
			(stroke
				(width 0.1524)
				(type default)
			)
			(layer "F.SilkS")
		)
		(fp_line
			(start 1.332738 -1.100074)
			(end 1.332738 1.100074)
			(stroke
				(width 0.1524)
				(type default)
			)
			(layer "F.SilkS")
		)
		(fp_poly
			(pts
				(xy -1.532636 -1.148334) (xy -2.277364 -1.396492) (xy -1.780794 -1.893062)
			)
			(stroke
				(width 0)
				(type default)
			)
			(fill yes)
			(layer "F.SilkS")
		)
		(fp_line
			(start -0.674878 1.100074)
			(end -0.674878 -1.100074)
			(stroke
				(width 0.1)
				(type default)
			)
			(layer "F.Fab")
		)
		(fp_line
			(start 0.674878 1.100074)
			(end -0.674878 1.100074)
			(stroke
				(width 0.1)
				(type default)
			)
			(layer "F.Fab")
		)
		(fp_line
			(start -0.674878 -1.100074)
			(end 0.674878 -1.100074)
			(stroke
				(width 0.1)
				(type default)
			)
			(layer "F.Fab")
		)
		(fp_line
			(start 0.674878 -1.100074)
			(end 0.674878 1.100074)
			(stroke
				(width 0.1)
				(type default)
			)
			(layer "F.Fab")
		)
		(fp_poly
			(pts
				(xy -2.2352 -0.298958) (xy -2.2352 -1.001014) (xy -1.533144 -0.649986)
			)
			(stroke
				(width 0)
				(type default)
			)
			(fill yes)
			(layer "F.Fab")
		)
		(pad "1" smd rect
			(at -0.94996 -0.649986)
			(size 0.4318 0.508)
			(layers "F.Cu" "F.Mask" "F.Paste")
			(net "GND")
		)
		(pad "2" smd rect
			(at -0.94996 0)
			(size 0.4318 0.508)
			(layers "F.Cu" "F.Mask" "F.Paste")
			(net "PRSNT_CABLE_GPU_A2_N")
		)
		(pad "3" smd rect
			(at -0.94996 0.649986)
			(size 0.4318 0.508)
			(layers "F.Cu" "F.Mask" "F.Paste")
			(net "PRSNT_CABLE_GPU_A2_ISO_N")
		)
		(pad "4" smd rect
			(at 0.94996 0.649986)
			(size 0.4318 0.508)
			(layers "F.Cu" "F.Mask" "F.Paste")
			(net "GND")
		)
		(pad "5" smd rect
			(at 0.94996 0)
			(size 0.4318 0.508)
			(layers "F.Cu" "F.Mask" "F.Paste")
			(net "PRSNT_CABLE_GPU_A2")
		)
		(pad "6" smd rect
			(at 0.94996 -0.649986)
			(size 0.4318 0.508)
			(layers "F.Cu" "F.Mask" "F.Paste")
			(net "PRSNT_CABLE_GPU_A2")
		)
	)
)
